# S9S_MB_2U (Grand Teton) — schematic netlist excerpt (pin names and nets, part order shuffled) for the footprints in the layout excerpt that follows; sources: Cadence DE-HDL packaged netlist, KiCad conversion of 03242023_DA0F0TMBIJ0_F0T_Motherboard_J_brd_V01_OCP.brd

PC1214_P0_4  Q_CAP  2.2UF 10V 10% X6S  pkg C0402  page 272 : A = PVCCFA_EHV_FIVRA_CPU0_PVCC2 ; B = GND
C1533  Q_CAP_DIFFBUS  DIFF BUS_0.22UF 6.3V 20% X6S  pkg C0201  page 177 : \1\ = P5E_CPU1_PE3_TX_C_DP<7> ; \2\ = P5E_CPU1_PE3_TX_DP<7>
R3150  Q_RES  1K 1% CHIP  pkg 0402LF  page 164 : A = PD_SMB_OCP2_HP_ADD2 ; B = GND

(kicad_pcb
	(version 20260206)
	(generator "pcbnew")
	(generator_version "10.0")
	(general
		(thickness 1.6)
		(legacy_teardrops no)
	)
	(paper "A4")
	(title_block
		(title "03242023_DA0F0TMBIJ0_F0T_Motherboard_J_brd_V01_OCP.brd")
		(comment 1 "Grand Teton / footprints 136-138 of 6105")
	)
	(layers
		(0 "F.Cu" signal "TOP")
		(4 "In1.Cu" signal "GND")
		(6 "In2.Cu" signal "IN1")
		(8 "In3.Cu" signal "GND1")
		(10 "In4.Cu" signal "IN2")
		(12 "In5.Cu" signal "GND2")
		(14 "In6.Cu" signal "IN3")
		(16 "In7.Cu" signal "GND3")
		(18 "In8.Cu" signal "VCC")
		(20 "In9.Cu" signal "VCC1")
		(22 "In10.Cu" signal "GND4")
		(24 "In11.Cu" signal "IN4")
		(26 "In12.Cu" signal "GND5")
		(28 "In13.Cu" signal "IN5")
		(30 "In14.Cu" signal "GND6")
		(32 "In15.Cu" signal "IN6")
		(34 "In16.Cu" signal "GND7")
		(2 "B.Cu" signal "BOTTOM")
		(9 "F.Adhes" user "F.Adhesive")
		(11 "B.Adhes" user "B.Adhesive")
		(13 "F.Paste" user "Package Geometry/Pastemask Top")
		(15 "B.Paste" user "Package Geometry/Pastemask Bottom")
		(5 "F.SilkS" user "Ref Des/Silkscreen Top")
		(7 "B.SilkS" user "Ref Des/Silkscreen Bottom")
		(1 "F.Mask" user "Board Geometry/Soldermask Top")
		(3 "B.Mask" user "Board Geometry/Soldermask Bottom")
		(17 "Dwgs.User" user "User.Drawings")
		(19 "Cmts.User" user "User.Comments")
		(21 "Eco1.User" user "User.Eco1")
		(23 "Eco2.User" user "User.Eco2")
		(25 "Edge.Cuts" user "Board Geometry/Outline")
		(27 "Margin" user)
		(31 "F.CrtYd" user "Package Geometry/Place Bound Top")
		(29 "B.CrtYd" user "Package Geometry/Place Bound Bottom")
		(35 "F.Fab" user "Ref Des/Assembly Top")
		(33 "B.Fab" user "Ref Des/Assembly Bottom")
	)
	(footprint ""
		(layer "F.Cu")
		(at 131.6736 -124.234448 180)
		(property "Reference" "R3150"
			(at 0 0 180)
			(layer "F.SilkS")
			(hide yes)
			(effects
				(font
					(size 1.27 1.27)
				)
			)
		)
		(property "Value" ""
			(at 0 0 180)
			(layer "F.Fab")
			(effects
				(font
					(size 1.27 1.27)
				)
			)
		)
		(duplicate_pad_numbers_are_jumpers no)
		(fp_line
			(start 0.7874 0.4064)
			(end -0.7874 0.4064)
			(stroke
				(width 0.1524)
				(type default)
			)
			(layer "F.SilkS")
		)
		(fp_line
			(start 0.7874 -0.4064)
			(end 0.7874 0.4064)
			(stroke
				(width 0.1524)
				(type default)
			)
			(layer "F.SilkS")
		)
		(fp_line
			(start -0.7874 0.4064)
			(end -0.7874 -0.4064)
			(stroke
				(width 0.1524)
				(type default)
			)
			(layer "F.SilkS")
		)
		(fp_line
			(start -0.7874 -0.4064)
			(end 0.7874 -0.4064)
			(stroke
				(width 0.1524)
				(type default)
			)
			(layer "F.SilkS")
		)
		(fp_line
			(start 0.67945 0.3048)
			(end 0.120396 0.3048)
			(stroke
				(width 0.1)
				(type default)
			)
			(layer "F.Fab")
		)
		(fp_line
			(start 0.67945 -0.3048)
			(end 0.67945 0.3048)
			(stroke
				(width 0.1)
				(type default)
			)
			(layer "F.Fab")
		)
		(fp_line
			(start 0.12065 -0.2794)
			(end 0.12065 -0.3048)
			(stroke
				(width 0.1)
				(type default)
			)
			(layer "F.Fab")
		)
		(fp_line
			(start 0.12065 -0.3048)
			(end 0.67945 -0.3048)
			(stroke
				(width 0.1)
				(type default)
			)
			(layer "F.Fab")
		)
		(fp_line
			(start 0.120396 0.3048)
			(end 0.120396 0.2794)
			(stroke
				(width 0.1)
				(type default)
			)
			(layer "F.Fab")
		)
		(fp_line
			(start 0.120396 0.2794)
			(end -0.12065 0.2794)
			(stroke
				(width 0.1)
				(type default)
			)
			(layer "F.Fab")
		)
		(fp_line
			(start -0.12065 0.3048)
			(end -0.67945 0.3048)
			(stroke
				(width 0.1)
				(type default)
			)
			(layer "F.Fab")
		)
		(fp_line
			(start -0.12065 0.2794)
			(end -0.12065 0.3048)
			(stroke
				(width 0.1)
				(type default)
			)
			(layer "F.Fab")
		)
		(fp_line
			(start -0.12065 -0.2794)
			(end 0.12065 -0.2794)
			(stroke
				(width 0.1)
				(type default)
			)
			(layer "F.Fab")
		)
		(fp_line
			(start -0.12065 -0.305054)
			(end -0.12065 -0.2794)
			(stroke
				(width 0.1)
				(type default)
			)
			(layer "F.Fab")
		)
		(fp_line
			(start -0.67945 0.3048)
			(end -0.67945 -0.305054)
			(stroke
				(width 0.1)
				(type default)
			)
			(layer "F.Fab")
		)
		(fp_line
			(start -0.67945 -0.305054)
			(end -0.12065 -0.305054)
			(stroke
				(width 0.1)
				(type default)
			)
			(layer "F.Fab")
		)
		(pad "1" smd circle
			(at -0.40005 0 180)
			(size 0 0)
			(layers "F.Cu" "F.Mask" "F.Paste")
			(net "PD_SMB_OCP2_HP_ADD2")
		)
		(pad "2" smd circle
			(at 0.40005 0 180)
			(size 0 0)
			(layers "F.Cu" "F.Mask" "F.Paste")
			(net "GND")
		)
	)
	(footprint ""
		(layer "F.Cu")
		(at 285.211266 -362.584746 -90)
		(property "Reference" "PC1214_P0_4"
			(at 0 0 270)
			(layer "F.SilkS")
			(hide yes)
			(effects
				(font
					(size 1.27 1.27)
				)
			)
		)
		(property "Value" ""
			(at 0 0 270)
			(layer "F.Fab")
			(effects
				(font
					(size 1.27 1.27)
				)
			)
		)
		(duplicate_pad_numbers_are_jumpers no)
		(fp_line
			(start -0.7874 0.4064)
			(end -0.7874 -0.4064)
			(stroke
				(width 0.1524)
				(type default)
			)
			(layer "F.SilkS")
		)
		(fp_line
			(start 0.7874 0.4064)
			(end -0.7874 0.4064)
			(stroke
				(width 0.1524)
				(type default)
			)
			(layer "F.SilkS")
		)
		(fp_line
			(start -0.7874 -0.4064)
			(end 0.7874 -0.4064)
			(stroke
				(width 0.1524)
				(type default)
			)
			(layer "F.SilkS")
		)
		(fp_line
			(start 0.7874 -0.4064)
			(end 0.7874 0.4064)
			(stroke
				(width 0.1524)
				(type default)
			)
			(layer "F.SilkS")
		)
		(fp_line
			(start -0.67945 0.3048)
			(end -0.67945 -0.305054)
			(stroke
				(width 0.1)
				(type default)
			)
			(layer "F.Fab")
		)
		(fp_line
			(start -0.12065 0.3048)
			(end -0.67945 0.3048)
			(stroke
				(width 0.1)
				(type default)
			)
			(layer "F.Fab")
		)
		(fp_line
			(start 0.120396 0.3048)
			(end 0.120396 0.2794)
			(stroke
				(width 0.1)
				(type default)
			)
			(layer "F.Fab")
		)
		(fp_line
			(start 0.67945 0.3048)
			(end 0.120396 0.3048)
			(stroke
				(width 0.1)
				(type default)
			)
			(layer "F.Fab")
		)
		(fp_line
			(start -0.12065 0.2794)
			(end -0.12065 0.3048)
			(stroke
				(width 0.1)
				(type default)
			)
			(layer "F.Fab")
		)
		(fp_line
			(start 0.120396 0.2794)
			(end -0.12065 0.2794)
			(stroke
				(width 0.1)
				(type default)
			)
			(layer "F.Fab")
		)
		(fp_line
			(start -0.12065 -0.2794)
			(end 0.12065 -0.2794)
			(stroke
				(width 0.1)
				(type default)
			)
			(layer "F.Fab")
		)
		(fp_line
			(start 0.12065 -0.2794)
			(end 0.12065 -0.3048)
			(stroke
				(width 0.1)
				(type default)
			)
			(layer "F.Fab")
		)
		(fp_line
			(start 0.12065 -0.3048)
			(end 0.67945 -0.3048)
			(stroke
				(width 0.1)
				(type default)
			)
			(layer "F.Fab")
		)
		(fp_line
			(start 0.67945 -0.3048)
			(end 0.67945 0.3048)
			(stroke
				(width 0.1)
				(type default)
			)
			(layer "F.Fab")
		)
		(fp_line
			(start -0.67945 -0.305054)
			(end -0.12065 -0.305054)
			(stroke
				(width 0.1)
				(type default)
			)
			(layer "F.Fab")
		)
		(fp_line
			(start -0.12065 -0.305054)
			(end -0.12065 -0.2794)
			(stroke
				(width 0.1)
				(type default)
			)
			(layer "F.Fab")
		)
		(pad "1" smd circle
			(at -0.40005 0 270)
			(size 0 0)
			(layers "F.Cu" "F.Mask" "F.Paste")
			(net "PVCCFA_EHV_FIVRA_CPU0_PVCC2")
		)
		(pad "2" smd circle
			(at 0.40005 0 270)
			(size 0 0)
			(layers "F.Cu" "F.Mask" "F.Paste")
			(net "GND")
		)
	)
	(footprint ""
		(layer "F.Cu")
		(at 146.896074 -408.517344 -90)
		(property "Reference" "C1533"
			(at 0 0 270)
			(layer "F.SilkS")
			(hide yes)
			(effects
				(font
					(size 1.27 1.27)
				)
			)
		)
		(property "Value" ""
			(at 0 0 270)
			(layer "F.Fab")
			(effects
				(font
					(size 1.27 1.27)
				)
			)
		)
		(duplicate_pad_numbers_are_jumpers no)
		(fp_line
			(start -0.299974 0.150114)
			(end -0.299974 -0.150114)
			(stroke
				(width 0.1)
				(type default)
			)
			(layer "F.Fab")
		)
		(fp_line
			(start 0.299974 0.150114)
			(end -0.299974 0.150114)
			(stroke
				(width 0.1)
				(type default)
			)
			(layer "F.Fab")
		)
		(fp_line
			(start -0.299974 -0.150114)
			(end 0.299974 -0.150114)
			(stroke
				(width 0.1)
				(type default)
			)
			(layer "F.Fab")
		)
		(fp_line
			(start 0.299974 -0.150114)
			(end 0.299974 0.150114)
			(stroke
				(width 0.1)
				(type default)
			)
			(layer "F.Fab")
		)
		(pad "1" smd rect
			(at -0.2667 0 270)
			(size 0.3048 0.381)
			(layers "F.Cu" "F.Mask" "F.Paste")
			(net "P5E_CPU1_PE3_TX_C_DP<7>")
		)
		(pad "2" smd rect
			(at 0.2667 0 270)
			(size 0.3048 0.381)
			(layers "F.Cu" "F.Mask" "F.Paste")
			(net "P5E_CPU1_PE3_TX_DP<7>")
		)
	)
)
